FILE_TYPE = CONNECTIVITY;
{Allegro Design Entry HDL 17.2-2016 S081 (4005846) 1/11/2022}
"PAGE_NUMBER" = 107;
0"NC";
1"M_K_CPU1_SA_CB<7:0>";
2"M_K_CPU1_SA_CA<6:0>";
3"M_K_CPU1_SB_CA<6:0>";
4"M_K_CPU1_SB_CB<7:0>";
5"M_K_CPU1_SA_DQ<31:0>";
6"M_K_CPU1_SB_DQ<31:0>";
7"M_K_CPU1_SA_DQS_DN<9:0>";
8"M_K_CPU1_SA_DQS_DP<9:0>";
9"M_K_CPU1_SB_DQS_DN<9:0>";
10"M_K_CPU1_SB_DQS_DP<9:0>";
11"GND\g";
12"GND\g";
13"P3V3_STBY\g";
14"I3C_SPD_DDRGL_CPU1_SCL";
15"I3C_SPD_DDRK_CPU1_SCL";
16"PWRGD_CHK_CPU1_DIMM";
17"TP_CHK_CPU1_DIMM_RFU_5";
18"TP_CHK_CPU1_DIMM_RFU_4";
19"TP_CHK_CPU1_DIMM_RFU_3";
20"TP_CHK_CPU1_DIMM_RFU_2";
21"TP_CHK_CPU1_DIMM_RFU_6";
22"I3C_SPD_DDRGL_CPU1_SDA";
23"PD_CHK_CPU1_DIMM_SAA";
24"P3V3_STBY\g";
25"TP_CHK_CPU1_DIMM_RFU_0";
26"TP_CHK_CPU1_DIMM_RFU_1";
27"M_K_CPU1_ALERT_N";
28"M_K_CPU1_RESET_N";
29"P12V_MEM_1\g";
30"GND\g";
31"GND\g";
32"M_K_CPU1_SA_DQS_DP<9>";
33"M_K_CPU1_SB_DQS_DP<9>";
34"M_K_CPU1_SB_DQS_DN<9>";
35"M_K_CPU1_SA_DQS_DN<9>";
36"M_K_CPU1_SA_DQS_DP<8>";
37"M_K_CPU1_SA_DQS_DN<8>";
38"M_K_CPU1_SB_DQS_DN<7>";
39"M_K_CPU1_SA_DQS_DP<7>";
40"M_K_CPU1_SB_DQS_DP<6>";
41"M_K_CPU1_SB_DQS_DN<6>";
42"M_K_CPU1_SA_DQS_DN<6>";
43"M_K_CPU1_SB_DQS_DP<5>";
44"M_K_CPU1_SB_DQS_DN<5>";
45"M_K_CPU1_SA_DQS_DP<5>";
46"M_K_CPU1_SA_DQS_DN<5>";
47"M_K_CPU1_SB_DQS_DP<4>";
48"M_K_CPU1_SB_DQS_DN<4>";
49"M_K_CPU1_SA_DQS_DP<4>";
50"M_K_CPU1_SA_DQS_DN<4>";
51"M_K_CPU1_SB_DQS_DP<3>";
52"M_K_CPU1_SB_DQS_DN<3>";
53"M_K_CPU1_SA_DQS_DP<3>";
54"M_K_CPU1_SA_DQS_DN<3>";
55"M_K_CPU1_SB_DQS_DP<2>";
56"M_K_CPU1_SB_DQS_DN<2>";
57"M_K_CPU1_SA_DQS_DP<2>";
58"M_K_CPU1_SA_DQS_DN<2>";
59"M_K_CPU1_SB_DQS_DP<1>";
60"M_K_CPU1_SB_DQS_DN<1>";
61"M_K_CPU1_SA_DQS_DP<1>";
62"M_K_CPU1_SA_DQS_DN<1>";
63"M_K_CPU1_SB_DQS_DP<0>";
64"M_K_CPU1_SB_DQS_DN<0>";
65"M_K_CPU1_SA_DQS_DP<0>";
66"M_K_CPU1_SA_DQS_DN<0>";
67"M_K_CPU1_SB_DQS_DP<7>";
68"M_K_CPU1_SB_DQS_DN<8>";
69"M_K_CPU1_SB_DQS_DP<8>";
70"M_K_CPU1_SA_DQS_DP<6>";
71"M_K_CPU1_SA_DQS_DN<7>";
72"M_K_CPU1_SB_PAR";
73"M_K_CPU1_SA_PAR";
74"M_K_CPU1_SB_RSP<0>";
75"M_K_CPU1_SA_RSP<0>";
76"M_K_CPU1_SB_DQ<0>";
77"M_K_CPU1_SB_DQ<1>";
78"M_K_CPU1_SB_DQ<2>";
79"M_K_CPU1_SB_DQ<3>";
80"M_K_CPU1_SB_DQ<4>";
81"M_K_CPU1_SB_DQ<5>";
82"M_K_CPU1_SB_DQ<6>";
83"M_K_CPU1_SB_DQ<7>";
84"M_K_CPU1_SB_DQ<8>";
85"M_K_CPU1_SB_DQ<9>";
86"M_K_CPU1_SB_DQ<10>";
87"M_K_CPU1_SB_DQ<11>";
88"M_K_CPU1_SB_DQ<12>";
89"M_K_CPU1_SB_DQ<13>";
90"M_K_CPU1_SB_DQ<14>";
91"M_K_CPU1_SB_DQ<15>";
92"M_K_CPU1_SB_DQ<16>";
93"M_K_CPU1_SB_DQ<17>";
94"M_K_CPU1_SB_DQ<18>";
95"M_K_CPU1_SB_DQ<19>";
96"M_K_CPU1_SB_DQ<20>";
97"M_K_CPU1_SB_DQ<21>";
98"M_K_CPU1_SB_DQ<22>";
99"M_K_CPU1_SB_DQ<23>";
100"M_K_CPU1_SB_DQ<24>";
101"M_K_CPU1_SB_DQ<25>";
102"M_K_CPU1_SB_DQ<26>";
103"M_K_CPU1_SB_DQ<27>";
104"M_K_CPU1_SB_DQ<28>";
105"M_K_CPU1_SB_DQ<29>";
106"M_K_CPU1_SB_DQ<30>";
107"M_K_CPU1_SB_DQ<31>";
108"M_K_CPU1_SA_DQ<0>";
109"M_K_CPU1_SA_DQ<1>";
110"M_K_CPU1_SA_DQ<2>";
111"M_K_CPU1_SA_DQ<3>";
112"M_K_CPU1_SA_DQ<4>";
113"M_K_CPU1_SA_DQ<5>";
114"M_K_CPU1_SA_DQ<6>";
115"M_K_CPU1_SA_DQ<7>";
116"M_K_CPU1_SA_DQ<8>";
117"M_K_CPU1_SA_DQ<9>";
118"M_K_CPU1_SA_DQ<10>";
119"M_K_CPU1_SA_DQ<11>";
120"M_K_CPU1_SA_DQ<12>";
121"M_K_CPU1_SA_DQ<13>";
122"M_K_CPU1_SA_DQ<14>";
123"M_K_CPU1_SA_DQ<15>";
124"M_K_CPU1_SA_DQ<16>";
125"M_K_CPU1_SA_DQ<17>";
126"M_K_CPU1_SA_DQ<18>";
127"M_K_CPU1_SA_DQ<19>";
128"M_K_CPU1_SA_DQ<20>";
129"M_K_CPU1_SA_DQ<21>";
130"M_K_CPU1_SA_DQ<22>";
131"M_K_CPU1_SA_DQ<23>";
132"M_K_CPU1_SA_DQ<24>";
133"M_K_CPU1_SA_DQ<25>";
134"M_K_CPU1_SA_DQ<26>";
135"M_K_CPU1_SA_DQ<27>";
136"M_K_CPU1_SA_DQ<28>";
137"M_K_CPU1_SA_DQ<29>";
138"M_K_CPU1_SA_DQ<30>";
139"M_K_CPU1_SB_CS_N<1>";
140"M_K_CPU1_SA_CS_N<1>";
141"M_K_CPU1_SB_CS_N<0>";
142"M_K_CPU1_SA_CS_N<0>";
143"M_K_CPU1_CLK_DP<0>";
144"M_K_CPU1_CLK_DN<0>";
145"M_K_CPU1_SB_CB<0>";
146"M_K_CPU1_SB_CB<1>";
147"M_K_CPU1_SB_CB<2>";
148"M_K_CPU1_SB_CB<3>";
149"M_K_CPU1_SB_CB<4>";
150"M_K_CPU1_SB_CB<5>";
151"M_K_CPU1_SB_CB<6>";
152"M_K_CPU1_SA_CB<0>";
153"M_K_CPU1_SA_CB<2>";
154"M_K_CPU1_SA_CB<3>";
155"M_K_CPU1_SA_CB<5>";
156"M_K_CPU1_SA_CB<6>";
157"M_K_CPU1_SB_CA<6>";
158"M_K_CPU1_SA_CA<6>";
159"M_K_CPU1_SB_CA<5>";
160"M_K_CPU1_SA_CA<5>";
161"M_K_CPU1_SB_CA<4>";
162"M_K_CPU1_SA_CA<4>";
163"M_K_CPU1_SB_CA<3>";
164"M_K_CPU1_SA_CA<3>";
165"M_K_CPU1_SB_CA<2>";
166"M_K_CPU1_SA_CA<2>";
167"M_K_CPU1_SB_CA<1>";
168"M_K_CPU1_SA_CA<1>";
169"M_K_CPU1_SB_CA<0>";
170"M_K_CPU1_SA_CA<0>";
171"M_K_CPU1_SB_CB<7>";
172"M_K_CPU1_SA_CB<1>";
173"M_K_CPU1_SA_CB<4>";
174"M_K_CPU1_SA_CB<7>";
175"M_K_CPU1_SA_DQ<31>";
176"GND\g";
177"PWRGD_CHGL_CPU1";
178"PD_CHK_CPU1_DIMM_SAA";
%"TAP"
"1","(-6000,4175)","0","mstr_standard","I100";
;
CDS_LIB"mstr_standard"
BODY_TYPE"PLUMBING"
HDL_TAP"TRUE";
"B \NAC \NWC"5;
"S \NAC"
BN"8"116;
%"TAP"
"1","(-6000,4225)","0","mstr_standard","I101";
;
CDS_LIB"mstr_standard"
BODY_TYPE"PLUMBING"
HDL_TAP"TRUE";
"B \NAC \NWC"5;
"S \NAC"
BN"9"117;
%"TAP"
"1","(-6000,4275)","0","mstr_standard","I102";
;
CDS_LIB"mstr_standard"
BODY_TYPE"PLUMBING"
HDL_TAP"TRUE";
"B \NAC \NWC"5;
"S \NAC"
BN"10"118;
%"TAP"
"1","(-6000,4375)","0","mstr_standard","I103";
;
CDS_LIB"mstr_standard"
BODY_TYPE"PLUMBING"
HDL_TAP"TRUE";
"B \NAC \NWC"5;
"S \NAC"
BN"12"120;
%"TAP"
"1","(-6000,4325)","0","mstr_standard","I104";
;
CDS_LIB"mstr_standard"
BODY_TYPE"PLUMBING"
HDL_TAP"TRUE";
"B \NAC \NWC"5;
"S \NAC"
BN"11"119;
%"TAP"
"1","(-6000,4425)","0","mstr_standard","I105";
;
CDS_LIB"mstr_standard"
BODY_TYPE"PLUMBING"
HDL_TAP"TRUE";
"B \NAC \NWC"5;
"S \NAC"
BN"13"121;
%"TAP"
"1","(-6000,4475)","0","mstr_standard","I106";
;
CDS_LIB"mstr_standard"
BODY_TYPE"PLUMBING"
HDL_TAP"TRUE";
"B \NAC \NWC"5;
"S \NAC"
BN"14"122;
%"TAP"
"1","(-6000,4525)","0","mstr_standard","I107";
;
CDS_LIB"mstr_standard"
BODY_TYPE"PLUMBING"
HDL_TAP"TRUE";
"B \NAC \NWC"5;
"S \NAC"
BN"15"123;
%"TAP"
"1","(-6000,4575)","0","mstr_standard","I108";
;
CDS_LIB"mstr_standard"
BODY_TYPE"PLUMBING"
HDL_TAP"TRUE";
"B \NAC \NWC"5;
"S \NAC"
BN"16"124;
%"TAP"
"1","(-6000,4675)","0","mstr_standard","I109";
;
CDS_LIB"mstr_standard"
BODY_TYPE"PLUMBING"
HDL_TAP"TRUE";
"B \NAC \NWC"5;
"S \NAC"
BN"18"126;
%"TAP"
"1","(-6000,4625)","0","mstr_standard","I110";
;
CDS_LIB"mstr_standard"
BODY_TYPE"PLUMBING"
HDL_TAP"TRUE";
"B \NAC \NWC"5;
"S \NAC"
BN"17"125;
%"TAP"
"1","(-6000,4725)","0","mstr_standard","I111";
;
CDS_LIB"mstr_standard"
BODY_TYPE"PLUMBING"
HDL_TAP"TRUE";
"B \NAC \NWC"5;
"S \NAC"
BN"19"127;
%"TAP"
"1","(-6000,4775)","0","mstr_standard","I112";
;
CDS_LIB"mstr_standard"
BODY_TYPE"PLUMBING"
HDL_TAP"TRUE";
"B \NAC \NWC"5;
"S \NAC"
BN"20"128;
%"TAP"
"1","(-6000,4825)","0","mstr_standard","I113";
;
CDS_LIB"mstr_standard"
BODY_TYPE"PLUMBING"
HDL_TAP"TRUE";
"B \NAC \NWC"5;
"S \NAC"
BN"21"129;
%"TAP"
"1","(-6000,4875)","0","mstr_standard","I114";
;
CDS_LIB"mstr_standard"
BODY_TYPE"PLUMBING"
HDL_TAP"TRUE";
"B \NAC \NWC"5;
"S \NAC"
BN"22"130;
%"TAP"
"1","(-6000,4925)","0","mstr_standard","I115";
;
CDS_LIB"mstr_standard"
BODY_TYPE"PLUMBING"
HDL_TAP"TRUE";
"B \NAC \NWC"5;
"S \NAC"
BN"23"131;
%"TAP"
"1","(-6000,4975)","0","mstr_standard","I116";
;
CDS_LIB"mstr_standard"
BODY_TYPE"PLUMBING"
HDL_TAP"TRUE";
"B \NAC \NWC"5;
"S \NAC"
BN"24"132;
%"TAP"
"1","(-6000,5025)","0","mstr_standard","I117";
;
CDS_LIB"mstr_standard"
BODY_TYPE"PLUMBING"
HDL_TAP"TRUE";
"B \NAC \NWC"5;
"S \NAC"
BN"25"133;
%"TAP"
"1","(-6000,5075)","0","mstr_standard","I118";
;
CDS_LIB"mstr_standard"
BODY_TYPE"PLUMBING"
HDL_TAP"TRUE";
"B \NAC \NWC"5;
"S \NAC"
BN"26"134;
%"TAP"
"1","(-6000,5125)","0","mstr_standard","I119";
;
CDS_LIB"mstr_standard"
BODY_TYPE"PLUMBING"
HDL_TAP"TRUE";
"B \NAC \NWC"5;
"S \NAC"
BN"27"135;
%"TAP"
"1","(-6000,5175)","0","mstr_standard","I120";
;
CDS_LIB"mstr_standard"
BODY_TYPE"PLUMBING"
HDL_TAP"TRUE";
"B \NAC \NWC"5;
"S \NAC"
BN"28"136;
%"TAP"
"1","(-6000,5275)","0","mstr_standard","I121";
;
CDS_LIB"mstr_standard"
BODY_TYPE"PLUMBING"
HDL_TAP"TRUE";
"B \NAC \NWC"5;
"S \NAC"
BN"30"138;
%"TAP"
"1","(-6000,5325)","0","mstr_standard","I122";
;
CDS_LIB"mstr_standard"
BODY_TYPE"PLUMBING"
HDL_TAP"TRUE";
"B \NAC \NWC"5;
"S \NAC"
BN"31"175;
%"TAP"
"1","(-6000,5225)","0","mstr_standard","I123";
;
CDS_LIB"mstr_standard"
BODY_TYPE"PLUMBING"
HDL_TAP"TRUE";
"B \NAC \NWC"5;
"S \NAC"
BN"29"137;
%"GND"
"1","(-6400,875)","0","mstr_symbols","I126";
;
BOM_COST"MEM"
SIZE"1B"
CDS_LIB"mstr_symbols"
BODY_TYPE"PLUMBING"
VOLTAGE"0.0"
HDL_POWER"GND";
"A\NAC"11;
%"Q_RES"
"2","(-6400,1100)","0","pure_quanta","I136";
;
LOCATION"R777"
$SEC"1"
CDS_SEC"1"
WATTAGE"1/16W"
MATERIAL"CHIP"
TOLERANCE"1%"
VALUE"54.9K"
PART_NUMBER"TMP_QCS35492FB14"
PACK_TYPE"0402LF"
CDS_LIB"pure_quanta";
"A"
$PN"1"178;
"B"
$PN"2"11;
%"GND"
"1","(-2150,1850)","0","mstr_symbols","I137";
;
CDS_LIB"mstr_symbols"
SIZE"1B"
BODY_TYPE"PLUMBING"
VOLTAGE"0.0"
HDL_POWER"GND";
"A\NAC"31;
%"GND"
"1","(-350,1625)","0","mstr_symbols","I138";
;
CDS_LIB"mstr_symbols"
SIZE"1B"
BODY_TYPE"PLUMBING"
VOLTAGE"0.0"
HDL_POWER"GND";
"A\NAC"30;
%"SCONN288_DDR506112002KQ"
"3","(-1250,3625)","0","pure_quanta","I139";
;
LOCATION"J99"
$SEC"3"
CDS_SEC"3"
VALUE"SCONN288_DDR506112002KQ"
PART_TYPE"SMLF"
MATERIAL"IO"
PART_NUMBER"DFHST8FS479"
CDS_LMAN_SYM_OUTLINE"-450,1800,450,-1750"
NEEDS_NO_SIZE"TRUE"
CDS_LIB"pure_quanta";
"G3"
$PN"G3"30;
"G2"
$PN"G2"30;
"G1"
$PN"G1"30;
"VSS62"
$PN"141"30;
"VSS61"
$PN"139"30;
"VSS60"
$PN"136"30;
"VSS58"
$PN"132"30;
"VSS104"
$PN"240"31;
"VSS102"
$PN"235"31;
"VSS100"
$PN"230"31;
"VIN_BULK2"
$PN"146"29;
"VIN_BULK1"
$PN"145"29;
"VIN_BULK0"
$PN"1"29;
"VSS126"
$PN"288"31;
"VSS125"
$PN"286"31;
"VSS124"
$PN"284"31;
"VSS123"
$PN"281"31;
"VSS122"
$PN"279"31;
"VSS121"
$PN"277"31;
"VSS120"
$PN"275"31;
"VSS119"
$PN"273"31;
"VSS118"
$PN"270"31;
"VSS117"
$PN"268"31;
"VSS116"
$PN"266"31;
"VSS115"
$PN"264"31;
"VSS114"
$PN"262"31;
"VSS113"
$PN"259"31;
"VSS112"
$PN"257"31;
"VSS111"
$PN"255"31;
"VSS110"
$PN"253"31;
"VSS109"
$PN"251"31;
"VSS108"
$PN"248"31;
"VSS107"
$PN"246"31;
"VSS106"
$PN"244"31;
"VSS105"
$PN"242"31;
"VSS103"
$PN"237"31;
"VSS101"
$PN"233"31;
"VSS99"
$PN"228"31;
"VSS98"
$PN"226"31;
"VSS97"
$PN"224"31;
"VSS96"
$PN"222"31;
"VSS95"
$PN"219"31;
"VSS94"
$PN"216"31;
"VSS93"
$PN"214"31;
"VSS92"
$PN"212"31;
"VSS91"
$PN"210"31;
"VSS90"
$PN"208"31;
"VSS89"
$PN"206"31;
"VSS88"
$PN"204"31;
"VSS87"
$PN"202"31;
"VSS86"
$PN"199"31;
"VSS85"
$PN"197"31;
"VSS84"
$PN"195"31;
"VSS83"
$PN"193"31;
"VSS82"
$PN"191"31;
"VSS81"
$PN"188"31;
"VSS80"
$PN"186"31;
"VSS79"
$PN"184"31;
"VSS78"
$PN"182"31;
"VSS77"
$PN"180"31;
"VSS76"
$PN"177"31;
"VSS75"
$PN"175"31;
"VSS74"
$PN"173"31;
"VSS73"
$PN"171"31;
"VSS72"
$PN"169"31;
"VSS71"
$PN"166"31;
"VSS70"
$PN"164"31;
"VSS69"
$PN"162"31;
"VSS68"
$PN"160"31;
"VSS67"
$PN"158"31;
"VSS66"
$PN"155"31;
"VSS65"
$PN"153"31;
"VSS64"
$PN"151"31;
"VSS63"
$PN"143"30;
"VSS59"
$PN"134"30;
"VSS57"
$PN"130"30;
"VSS56"
$PN"128"30;
"VSS55"
$PN"125"30;
"VSS54"
$PN"123"30;
"VSS53"
$PN"121"30;
"VSS52"
$PN"119"30;
"VSS51"
$PN"117"30;
"VSS50"
$PN"114"30;
"VSS49"
$PN"112"30;
"VSS48"
$PN"110"30;
"VSS47"
$PN"108"30;
"VSS46"
$PN"106"30;
"VSS45"
$PN"103"30;
"VSS44"
$PN"101"30;
"VSS43"
$PN"99"30;
"VSS42"
$PN"97"30;
"VSS41"
$PN"95"30;
"VSS40"
$PN"92"30;
"VSS39"
$PN"90"30;
"VSS38"
$PN"88"30;
"VSS37"
$PN"85"30;
"VSS36"
$PN"83"30;
"VSS35"
$PN"81"30;
"VSS34"
$PN"79"30;
"VSS33"
$PN"77"30;
"VSS32"
$PN"75"30;
"VSS31"
$PN"73"30;
"VSS30"
$PN"71"30;
"VSS29"
$PN"69"30;
"VSS28"
$PN"67"30;
"VSS27"
$PN"65"30;
"VSS26"
$PN"63"30;
"VSS25"
$PN"61"30;
"VSS24"
$PN"59"30;
"VSS23"
$PN"57"30;
"VSS22"
$PN"54"30;
"VSS21"
$PN"52"30;
"VSS20"
$PN"50"30;
"VSS19"
$PN"48"30;
"VSS18"
$PN"46"30;
"VSS17"
$PN"43"30;
"VSS16"
$PN"41"30;
"VSS15"
$PN"39"30;
"VSS14"
$PN"37"30;
"VSS13"
$PN"35"30;
"VSS12"
$PN"32"30;
"VSS11"
$PN"30"30;
"VSS10"
$PN"28"30;
"VSS9"
$PN"26"30;
"VSS8"
$PN"24"30;
"VSS7"
$PN"21"30;
"VSS6"
$PN"19"30;
"VSS5"
$PN"17"30;
"VSS4"
$PN"15"30;
"VSS3"
$PN"13"30;
"VSS2"
$PN"10"30;
"VSS1"
$PN"8"30;
"VSS0"
$PN"6"30;
%"Q_CAP"
"1","(-8675,3150)","2","pure_quanta","I185";
;
LOCATION"C176"
$SEC"1"
CDS_SEC"1"
MATERIAL"X7R"
TOLERANCE"10%"
VALUE"0.1UF"
VOLTAGE"25V"
PACK_TYPE"0402"
PART_NUMBER"CH4104K1B00"
CDS_LIB"pure_quanta"
BOM_COST"MEM"
ROOM"MEM_CH_A_CPU0_DIMM1";
"B"
$PN"2"12;
"A"
$PN"1"24;
%"GND"
"1","(-8675,2925)","0","mstr_symbols","I186";
;
CDS_LIB"mstr_symbols"
SIZE"1B"
BOM_COST"MEM"
BODY_TYPE"PLUMBING"
VOLTAGE"0"
ROOM"MEM_EFGH_DECOUPLING_CAPS"
HDL_POWER"GND";
"A\NAC"12;
%"Q_RES"
"1","(-8500,2075)","2","pure_quanta","I188";
;
LOCATION"R313"
$SEC"1"
CDS_SEC"1"
VALUE"0"
CDS_LIB"pure_quanta"
BOM_COST"MEM"
WATTAGE"1/16W"
MATERIAL"CHIP"
TOLERANCE"5%"
PART_NUMBER"CS00002JB38"
PACK_TYPE"0402LF"
ROOM"RST_CPU0_PLD_TO_DIMM";
"B"
$PN"2"177;
"A"
$PN"1"16;
%"VCC_CORE"
"1","(-8375,2400)","0","mstr_symbols","I189";
;
HDL_POWER"P3V3_STBY"
CDS_LIB"mstr_symbols"
VOLTAGE"3.3"
ROOM"PVCCINFAON_CPU0_CTRL";
"A"13;
%"Q_RES"
"2","(-8375,2225)","0","pure_quanta","I190";
;
LOCATION"R114"
$SEC"1"
CDS_SEC"1"
TOLERANCE"5%"
VALUE"1K"
WATTAGE"1/16W"
MATERIAL"EMPTY"
PACK_TYPE"0402LF"
CDS_LIB"pure_quanta"
BOM_COST"MEM"
PART_NUMBER"TMP_QCS21002JB34"
ROOM"MEM_CH_A_CPU0_DIMM1";
"A"
$PN"1"13;
"B"
$PN"2"16;
%"TAP"
"1","(-3275,4350)","0","mstr_standard","I195";
;
CDS_LIB"mstr_standard"
BODY_TYPE"PLUMBING"
HDL_TAP"TRUE";
"B \NAC \NWC"7;
"S \NAC"
BN"8"37;
%"TAP"
"1","(-3275,4450)","0","mstr_standard","I196";
;
CDS_LIB"mstr_standard"
BODY_TYPE"PLUMBING"
HDL_TAP"TRUE";
"B \NAC \NWC"7;
"S \NAC"
BN"9"35;
%"TAP"
"1","(-3475,4500)","0","mstr_standard","I197";
;
CDS_LIB"mstr_standard"
BODY_TYPE"PLUMBING"
HDL_TAP"TRUE";
"B \NAC \NWC"8;
"S \NAC"
BN"9"32;
%"TAP"
"1","(-3475,4400)","0","mstr_standard","I198";
;
CDS_LIB"mstr_standard"
BODY_TYPE"PLUMBING"
HDL_TAP"TRUE";
"B \NAC \NWC"8;
"S \NAC"
BN"8"36;
%"TAP"
"1","(-3275,4250)","0","mstr_standard","I199";
;
CDS_LIB"mstr_standard"
BODY_TYPE"PLUMBING"
HDL_TAP"TRUE";
"B \NAC \NWC"7;
"S \NAC"
BN"7"71;
%"TAP"
"1","(-3275,4150)","0","mstr_standard","I200";
;
CDS_LIB"mstr_standard"
BODY_TYPE"PLUMBING"
HDL_TAP"TRUE";
"B \NAC \NWC"7;
"S \NAC"
BN"6"42;
%"TAP"
"1","(-3475,4300)","0","mstr_standard","I201";
;
CDS_LIB"mstr_standard"
BODY_TYPE"PLUMBING"
HDL_TAP"TRUE";
"B \NAC \NWC"8;
"S \NAC"
BN"7"39;
%"TAP"
"1","(-3475,4200)","0","mstr_standard","I202";
;
CDS_LIB"mstr_standard"
BODY_TYPE"PLUMBING"
HDL_TAP"TRUE";
"B \NAC \NWC"8;
"S \NAC"
BN"6"70;
%"TAP"
"1","(-3475,4100)","0","mstr_standard","I203";
;
CDS_LIB"mstr_standard"
BODY_TYPE"PLUMBING"
HDL_TAP"TRUE";
"B \NAC \NWC"8;
"S \NAC"
BN"5"45;
%"TAP"
"1","(-3275,4050)","0","mstr_standard","I204";
;
CDS_LIB"mstr_standard"
BODY_TYPE"PLUMBING"
HDL_TAP"TRUE";
"B \NAC \NWC"7;
"S \NAC"
BN"5"46;
%"TAP"
"1","(-3275,3850)","0","mstr_standard","I205";
;
CDS_LIB"mstr_standard"
BODY_TYPE"PLUMBING"
HDL_TAP"TRUE";
"B \NAC \NWC"7;
"S \NAC"
BN"3"54;
%"TAP"
"1","(-3275,3950)","0","mstr_standard","I206";
;
CDS_LIB"mstr_standard"
BODY_TYPE"PLUMBING"
HDL_TAP"TRUE";
"B \NAC \NWC"7;
"S \NAC"
BN"4"50;
%"TAP"
"1","(-3475,4000)","0","mstr_standard","I207";
;
CDS_LIB"mstr_standard"
BODY_TYPE"PLUMBING"
HDL_TAP"TRUE";
"B \NAC \NWC"8;
"S \NAC"
BN"4"49;
%"TAP"
"1","(-3475,3900)","0","mstr_standard","I208";
;
CDS_LIB"mstr_standard"
BODY_TYPE"PLUMBING"
HDL_TAP"TRUE";
"B \NAC \NWC"8;
"S \NAC"
BN"3"53;
%"TAP"
"1","(-3275,3750)","0","mstr_standard","I209";
;
CDS_LIB"mstr_standard"
BODY_TYPE"PLUMBING"
HDL_TAP"TRUE";
"B \NAC \NWC"7;
"S \NAC"
BN"2"58;
%"TAP"
"1","(-3275,3650)","0","mstr_standard","I210";
;
CDS_LIB"mstr_standard"
BODY_TYPE"PLUMBING"
HDL_TAP"TRUE";
"B \NAC \NWC"7;
"S \NAC"
BN"1"62;
%"TAP"
"1","(-3475,3800)","0","mstr_standard","I211";
;
CDS_LIB"mstr_standard"
BODY_TYPE"PLUMBING"
HDL_TAP"TRUE";
"B \NAC \NWC"8;
"S \NAC"
BN"2"57;
%"TAP"
"1","(-3475,3700)","0","mstr_standard","I212";
;
CDS_LIB"mstr_standard"
BODY_TYPE"PLUMBING"
HDL_TAP"TRUE";
"B \NAC \NWC"8;
"S \NAC"
BN"1"61;
%"TAP"
"1","(-3475,3600)","0","mstr_standard","I213";
;
CDS_LIB"mstr_standard"
BODY_TYPE"PLUMBING"
HDL_TAP"TRUE";
"B \NAC \NWC"8;
"S \NAC"
BN"0"65;
%"TAP"
"1","(-3275,3550)","0","mstr_standard","I214";
;
CDS_LIB"mstr_standard"
BODY_TYPE"PLUMBING"
HDL_TAP"TRUE";
"B \NAC \NWC"7;
"S \NAC"
BN"0"66;
%"TAP"
"1","(-3275,3400)","0","mstr_standard","I215";
;
CDS_LIB"mstr_standard"
BODY_TYPE"PLUMBING"
HDL_TAP"TRUE";
"B \NAC \NWC"9;
"S \NAC"
BN"9"34;
%"TAP"
"1","(-3475,3450)","0","mstr_standard","I216";
;
CDS_LIB"mstr_standard"
BODY_TYPE"PLUMBING"
HDL_TAP"TRUE";
"B \NAC \NWC"10;
"S \NAC"
BN"9"33;
%"TAP"
"1","(-3475,3350)","0","mstr_standard","I217";
;
CDS_LIB"mstr_standard"
BODY_TYPE"PLUMBING"
HDL_TAP"TRUE";
"B \NAC \NWC"10;
"S \NAC"
BN"8"69;
%"TAP"
"1","(-3275,3200)","0","mstr_standard","I218";
;
CDS_LIB"mstr_standard"
BODY_TYPE"PLUMBING"
HDL_TAP"TRUE";
"B \NAC \NWC"9;
"S \NAC"
BN"7"38;
%"TAP"
"1","(-3275,3300)","0","mstr_standard","I219";
;
CDS_LIB"mstr_standard"
BODY_TYPE"PLUMBING"
HDL_TAP"TRUE";
"B \NAC \NWC"9;
"S \NAC"
BN"8"68;
%"SCONN288_DDR506112002KQ"
"1","(-6850,3575)","0","pure_quanta","I22";
;
LOCATION"J99"
$SEC"1"
CDS_SEC"1"
PART_TYPE"SMLF"
MATERIAL"IO"
VALUE"SCONN288_DDR506112002KQ"
PART_NUMBER"DFHST8FS479"
CDS_LMAN_SYM_OUTLINE"-450,1900,450,-1850"
NEEDS_NO_SIZE"TRUE"
CDS_LIB"pure_quanta";
"PWR_GOOD||FAIL_N"
$PN"147"16;
"DQ31_A"
$PN"194"175;
"CB7_A"
$PN"205"174;
"CB4_A"
$PN"58"173;
"CB1_A"
$PN"53"172;
"CB7_B"
$PN"236"171;
"ALERT_N \B"
$PN"62"27;
"CA0_A"
$PN"66"170;
"CA0_B"
$PN"76"169;
"CA1_A"
$PN"211"168;
"CA1_B"
$PN"221"167;
"CA2_A"
$PN"68"166;
"CA2_B"
$PN"78"165;
"CA3_A"
$PN"213"164;
"CA3_B"
$PN"223"163;
"CA4_A"
$PN"70"162;
"CA4_B"
$PN"80"161;
"CA5_A"
$PN"215"160;
"CA5_B"
$PN"225"159;
"CA6_A"
$PN"72"158;
"CA6_B"
$PN"82"157;
"CB6_A"
$PN"203"156;
"CB5_A"
$PN"60"155;
"CB3_A"
$PN"198"154;
"CB2_A"
$PN"196"153;
"CB0_A"
$PN"51"152;
"CB6_B"
$PN"234"151;
"CB5_B"
$PN"91"150;
"CB4_B"
$PN"89"149;
"CB3_B"
$PN"243"148;
"CB2_B"
$PN"241"147;
"CB1_B"
$PN"98"146;
"CB0_B"
$PN"96"145;
"CK_C \B"
$PN"218"144;
"CK_T"
$PN"217"143;
"CS0_A_N"
$PN"64"142;
"CS0_B_N"
$PN"84"141;
"CS1_A_N"
$PN"209"140;
"CS1_B_N"
$PN"229"139;
"DQ30_A"
$PN"192"138;
"DQ29_A"
$PN"49"137;
"DQ28_A"
$PN"47"136;
"DQ27_A"
$PN"187"135;
"DQ26_A"
$PN"185"134;
"DQ25_A"
$PN"42"133;
"DQ24_A"
$PN"40"132;
"DQ23_A"
$PN"183"131;
"DQ22_A"
$PN"181"130;
"DQ21_A"
$PN"38"129;
"DQ20_A"
$PN"36"128;
"DQ19_A"
$PN"176"127;
"DQ18_A"
$PN"174"126;
"DQ17_A"
$PN"31"125;
"DQ16_A"
$PN"29"124;
"DQ15_A"
$PN"172"123;
"DQ14_A"
$PN"170"122;
"DQ13_A"
$PN"27"121;
"DQ12_A"
$PN"25"120;
"DQ11_A"
$PN"165"119;
"DQ10_A"
$PN"163"118;
"DQ9_A"
$PN"20"117;
"DQ8_A"
$PN"18"116;
"DQ7_A"
$PN"161"115;
"DQ6_A"
$PN"159"114;
"DQ5_A"
$PN"16"113;
"DQ4_A"
$PN"14"112;
"DQ3_A"
$PN"154"111;
"DQ2_A"
$PN"152"110;
"DQ1_A"
$PN"9"109;
"DQ0_A"
$PN"7"108;
"DQ31_B"
$PN"287"107;
"DQ30_B"
$PN"285"106;
"DQ29_B"
$PN"142"105;
"DQ28_B"
$PN"140"104;
"DQ27_B"
$PN"280"103;
"DQ26_B"
$PN"278"102;
"DQ25_B"
$PN"135"101;
"DQ24_B"
$PN"133"100;
"DQ23_B"
$PN"276"99;
"DQ22_B"
$PN"274"98;
"DQ21_B"
$PN"131"97;
"DQ20_B"
$PN"129"96;
"DQ19_B"
$PN"269"95;
"DQ18_B"
$PN"267"94;
"DQ17_B"
$PN"124"93;
"DQ16_B"
$PN"122"92;
"DQ15_B"
$PN"265"91;
"DQ14_B"
$PN"263"90;
"DQ13_B"
$PN"120"89;
"DQ12_B"
$PN"118"88;
"DQ11_B"
$PN"258"87;
"DQ10_B"
$PN"256"86;
"DQ9_B"
$PN"113"85;
"DQ8_B"
$PN"111"84;
"DQ7_B"
$PN"254"83;
"DQ6_B"
$PN"252"82;
"DQ5_B"
$PN"109"81;
"DQ4_B"
$PN"107"80;
"DQ3_B"
$PN"247"79;
"DQ2_B"
$PN"245"78;
"DQ1_B"
$PN"102"77;
"DQ0_B"
$PN"100"76;
"HAS"
$PN"148"23;
"HSCL"
$PN"4"15;
"HSDA"
$PN"5"22;
"LBD||RSP_A_N"
$PN"86"75;
"LBS||RSP_B_N"
$PN"87"74;
"PAR_A"
$PN"74"73;
"PAR_B"
$PN"227"72;
"RESET_N \B"
$PN"207"28;
"RFU6"
$PN"232"21;
"RFU5"
$PN"231"17;
"RFU4"
$PN"220"18;
"RFU3"
$PN"150"19;
"RFU2"
$PN"149"20;
"RFU1"
$PN"144"26;
"RFU0"
$PN"2"25;
"VIN_MGMT"
$PN"3"24;
%"TAP"
"1","(-3275,3100)","0","mstr_standard","I220";
;
CDS_LIB"mstr_standard"
BODY_TYPE"PLUMBING"
HDL_TAP"TRUE";
"B \NAC \NWC"9;
"S \NAC"
BN"6"41;
%"TAP"
"1","(-3475,3250)","0","mstr_standard","I221";
;
CDS_LIB"mstr_standard"
BODY_TYPE"PLUMBING"
HDL_TAP"TRUE";
"B \NAC \NWC"10;
"S \NAC"
BN"7"67;
%"TAP"
"1","(-3475,3150)","0","mstr_standard","I222";
;
CDS_LIB"mstr_standard"
BODY_TYPE"PLUMBING"
HDL_TAP"TRUE";
"B \NAC \NWC"10;
"S \NAC"
BN"6"40;
%"TAP"
"1","(-3275,3000)","0","mstr_standard","I223";
;
CDS_LIB"mstr_standard"
BODY_TYPE"PLUMBING"
HDL_TAP"TRUE";
"B \NAC \NWC"9;
"S \NAC"
BN"5"44;
%"TAP"
"1","(-3275,2900)","0","mstr_standard","I224";
;
CDS_LIB"mstr_standard"
BODY_TYPE"PLUMBING"
HDL_TAP"TRUE";
"B \NAC \NWC"9;
"S \NAC"
BN"4"48;
%"TAP"
"1","(-3475,2950)","0","mstr_standard","I225";
;
CDS_LIB"mstr_standard"
BODY_TYPE"PLUMBING"
HDL_TAP"TRUE";
"B \NAC \NWC"10;
"S \NAC"
BN"4"47;
%"TAP"
"1","(-3475,3050)","0","mstr_standard","I226";
;
CDS_LIB"mstr_standard"
BODY_TYPE"PLUMBING"
HDL_TAP"TRUE";
"B \NAC \NWC"10;
"S \NAC"
BN"5"43;
%"TAP"
"1","(-3475,2850)","0","mstr_standard","I227";
;
CDS_LIB"mstr_standard"
BODY_TYPE"PLUMBING"
HDL_TAP"TRUE";
"B \NAC \NWC"10;
"S \NAC"
BN"3"51;
%"TAP"
"1","(-3275,2700)","0","mstr_standard","I228";
;
CDS_LIB"mstr_standard"
BODY_TYPE"PLUMBING"
HDL_TAP"TRUE";
"B \NAC \NWC"9;
"S \NAC"
BN"2"56;
%"TAP"
"1","(-3275,2800)","0","mstr_standard","I229";
;
CDS_LIB"mstr_standard"
BODY_TYPE"PLUMBING"
HDL_TAP"TRUE";
"B \NAC \NWC"9;
"S \NAC"
BN"3"52;
%"TAP"
"1","(-7700,3125)","2","mstr_standard","I23";
;
CDS_LIB"mstr_standard"
BODY_TYPE"PLUMBING"
HDL_TAP"TRUE";
"B \NAC \NWC"4;
"S \NAC"
BN"0"145;
%"TAP"
"1","(-3275,2600)","0","mstr_standard","I230";
;
CDS_LIB"mstr_standard"
BODY_TYPE"PLUMBING"
HDL_TAP"TRUE";
"B \NAC \NWC"9;
"S \NAC"
BN"1"60;
%"TAP"
"1","(-3475,2750)","0","mstr_standard","I231";
;
CDS_LIB"mstr_standard"
BODY_TYPE"PLUMBING"
HDL_TAP"TRUE";
"B \NAC \NWC"10;
"S \NAC"
BN"2"55;
%"TAP"
"1","(-3475,2650)","0","mstr_standard","I232";
;
CDS_LIB"mstr_standard"
BODY_TYPE"PLUMBING"
HDL_TAP"TRUE";
"B \NAC \NWC"10;
"S \NAC"
BN"1"59;
%"TAP"
"1","(-3475,2550)","0","mstr_standard","I233";
;
CDS_LIB"mstr_standard"
BODY_TYPE"PLUMBING"
HDL_TAP"TRUE";
"B \NAC \NWC"10;
"S \NAC"
BN"0"63;
%"TAP"
"1","(-3275,2500)","0","mstr_standard","I234";
;
CDS_LIB"mstr_standard"
BODY_TYPE"PLUMBING"
HDL_TAP"TRUE";
"B \NAC \NWC"9;
"S \NAC"
BN"0"64;
%"SCONN288_DDR506112002KQ"
"2","(-4425,3500)","0","pure_quanta","I235";
;
LOCATION"J99"
$SEC"2"
CDS_SEC"2"
MATERIAL"IO"
VALUE"SCONN288_DDR506112002KQ"
PART_TYPE"SMLF"
PART_NUMBER"DFHST8FS479"
CDS_LMAN_SYM_OUTLINE"-600,1150,600,-1150"
NEEDS_NO_SIZE"TRUE"
CDS_LIB"pure_quanta";
"DQS7_A_C||TDQS7_A_C \B"
$PN"178"71;
"DQS6_A_T||TDQS6_A_T"
$PN"168"70;
"DQS8_B_T||TDQS8_B_T"
$PN"283"69;
"DQS8_B_C||TDQS8_B_C \B"
$PN"282"68;
"DQS7_B_T||TDQS7_B_T"
$PN"272"67;
"DQS0_A_C \B"
$PN"12"66;
"DQS0_A_T"
$PN"11"65;
"DQS0_B_C \B"
$PN"105"64;
"DQS0_B_T"
$PN"104"63;
"DQS1_A_C \B"
$PN"23"62;
"DQS1_A_T"
$PN"22"61;
"DQS1_B_C \B"
$PN"116"60;
"DQS1_B_T"
$PN"115"59;
"DQS2_A_C \B"
$PN"34"58;
"DQS2_A_T"
$PN"33"57;
"DQS2_B_C \B"
$PN"127"56;
"DQS2_B_T"
$PN"126"55;
"DQS3_A_C \B"
$PN"45"54;
"DQS3_A_T"
$PN"44"53;
"DQS3_B_C \B"
$PN"138"52;
"DQS3_B_T"
$PN"137"51;
"DQS4_A_C \B"
$PN"56"50;
"DQS4_A_T"
$PN"55"49;
"DQS4_B_C \B"
$PN"238"48;
"DQS4_B_T"
$PN"239"47;
"DQS5_A_C||TDQS5_A_C||DQS5_A_T||TDQS5_A_T \B"
$PN"156"46;
"DQS5_A_T||TDQS5_A_T"
$PN"157"45;
"DQS5_B_C||TDQS5_B_C \B"
$PN"249"44;
"DQS5_B_T||TDQS5_B_T"
$PN"250"43;
"DQS6_A_C||TDQS6_A_C||DQS6_A_T||TDQS6_A_T \B"
$PN"167"42;
"DQS6_B_C||TDQS6_B_C \B"
$PN"260"41;
"DQS6_B_T||TDQS6_B_T"
$PN"261"40;
"DQS7_A_T||TDQS7_A_T"
$PN"179"39;
"DQS7_B_C||TDQS7_B_C \B"
$PN"271"38;
"DQS8_A_C||TDQS8_A_C \B"
$PN"189"37;
"DQS8_A_T||TDQS8_A_T"
$PN"190"36;
"DQS9_A_C||TDQS9_A_C \B"
$PN"200"35;
"DQS9_A_T||TDQS9_A_T"
$PN"201"32;
"DQS9_B_C||TDQS9_B_C \B"
$PN"94"34;
"DQS9_B_T||TDQS9_B_T||DBI4_B_N"
$PN"93"33;
%"GND"
"1","(-2850,5475)","0","pure_quanta_power","I236";
;
SIZE"1B"
BOM_COST"MEM"
CDS_LIB"pure_quanta_power"
ROOM"MEM_EFGH_DECOUPLING_CAPS"
HDL_POWER"GND";
"A<SIZE-1..0>\NAC"176;
%"Q_CAP"
"1","(-2850,5825)","2","pure_quanta","I237";
;
LOCATION"C546"
$SEC"1"
CDS_SEC"1"
MATERIAL"X6S"
TOLERANCE"10%"
VALUE"10UF"
PART_NUMBER"CH6104KEA00"
VOLTAGE"25V"
PACK_TYPE"C0805"
CDS_LIB"pure_quanta"
BOM_COST"MEM"
ROOM"MEM_CH_A_CPU0_DIMM1";
"B"
$PN"2"176;
"A"
$PN"1"29;
%"Q_CAP"
"1","(-2275,5825)","2","pure_quanta","I238";
;
LOCATION"C547"
$SEC"1"
CDS_SEC"1"
MATERIAL"X6S"
TOLERANCE"10%"
VALUE"10UF"
PART_NUMBER"CH6104KEA00"
VOLTAGE"25V"
PACK_TYPE"C0805"
CDS_LIB"pure_quanta"
BOM_COST"MEM"
ROOM"MEM_CH_A_CPU0_DIMM1";
"B"
$PN"2"176;
"A"
$PN"1"29;
%"UNIVERSAL_POWER"
"1","(-2850,6150)","0","pure_quanta_power","I239";
;
HDL_POWER"P12V_MEM_1"
CDS_LIB"pure_quanta_power";
"A"29;
%"TAP"
"1","(-7700,3175)","2","mstr_standard","I24";
;
CDS_LIB"mstr_standard"
BODY_TYPE"PLUMBING"
HDL_TAP"TRUE";
"B \NAC \NWC"4;
"S \NAC"
BN"1"146;
%"Q_RES"
"1","(-7750,2625)","0","pure_quanta","I241";
;
$LOCATION"R1590"
CDS_LOCATION"R1590"
$SEC"1"
CDS_SEC"1"
VALUE"49.9"
CDS_LIB"pure_quanta"
PART_NUMBER"CS04992FB07"
TOLERANCE"1%"
WATTAGE"1/16W"
PACK_TYPE"0402LF"
MATERIAL"CHIP";
"B"
$PN"2"15;
"A"
$PN"1"14;
%"TAP"
"1","(-7700,3225)","2","mstr_standard","I25";
;
CDS_LIB"mstr_standard"
BODY_TYPE"PLUMBING"
HDL_TAP"TRUE";
"B \NAC \NWC"4;
"S \NAC"
BN"2"147;
%"TAP"
"1","(-7700,3325)","2","mstr_standard","I26";
;
CDS_LIB"mstr_standard"
BODY_TYPE"PLUMBING"
HDL_TAP"TRUE";
"B \NAC \NWC"4;
"S \NAC"
BN"4"149;
%"TAP"
"1","(-7700,3375)","2","mstr_standard","I27";
;
CDS_LIB"mstr_standard"
BODY_TYPE"PLUMBING"
HDL_TAP"TRUE";
"B \NAC \NWC"4;
"S \NAC"
BN"5"150;
%"TAP"
"1","(-7700,3275)","2","mstr_standard","I28";
;
CDS_LIB"mstr_standard"
BODY_TYPE"PLUMBING"
HDL_TAP"TRUE";
"B \NAC \NWC"4;
"S \NAC"
BN"3"148;
%"TAP"
"1","(-7700,3575)","2","mstr_standard","I29";
;
CDS_LIB"mstr_standard"
BODY_TYPE"PLUMBING"
HDL_TAP"TRUE";
"B \NAC \NWC"1;
"S \NAC"
BN"0"152;
%"TAP"
"1","(-7700,3625)","2","mstr_standard","I30";
;
CDS_LIB"mstr_standard"
BODY_TYPE"PLUMBING"
HDL_TAP"TRUE";
"B \NAC \NWC"1;
"S \NAC"
BN"1"172;
%"TAP"
"1","(-7700,3425)","2","mstr_standard","I31";
;
CDS_LIB"mstr_standard"
BODY_TYPE"PLUMBING"
HDL_TAP"TRUE";
"B \NAC \NWC"4;
"S \NAC"
BN"6"151;
%"TAP"
"1","(-7700,3475)","2","mstr_standard","I32";
;
CDS_LIB"mstr_standard"
BODY_TYPE"PLUMBING"
HDL_TAP"TRUE";
"B \NAC \NWC"4;
"S \NAC"
BN"7"171;
%"TAP"
"1","(-6000,2125)","0","mstr_standard","I33";
;
CDS_LIB"mstr_standard"
BODY_TYPE"PLUMBING"
HDL_TAP"TRUE";
"B \NAC \NWC"6;
"S \NAC"
BN"0"76;
%"TAP"
"1","(-6000,2175)","0","mstr_standard","I34";
;
CDS_LIB"mstr_standard"
BODY_TYPE"PLUMBING"
HDL_TAP"TRUE";
"B \NAC \NWC"6;
"S \NAC"
BN"1"77;
%"TAP"
"1","(-6000,2225)","0","mstr_standard","I35";
;
CDS_LIB"mstr_standard"
BODY_TYPE"PLUMBING"
HDL_TAP"TRUE";
"B \NAC \NWC"6;
"S \NAC"
BN"2"78;
%"TAP"
"1","(-6000,2275)","0","mstr_standard","I36";
;
CDS_LIB"mstr_standard"
BODY_TYPE"PLUMBING"
HDL_TAP"TRUE";
"B \NAC \NWC"6;
"S \NAC"
BN"3"79;
%"TAP"
"1","(-6000,2325)","0","mstr_standard","I37";
;
CDS_LIB"mstr_standard"
BODY_TYPE"PLUMBING"
HDL_TAP"TRUE";
"B \NAC \NWC"6;
"S \NAC"
BN"4"80;
%"TAP"
"1","(-6000,2375)","0","mstr_standard","I38";
;
CDS_LIB"mstr_standard"
BODY_TYPE"PLUMBING"
HDL_TAP"TRUE";
"B \NAC \NWC"6;
"S \NAC"
BN"5"81;
%"TAP"
"1","(-6000,2425)","0","mstr_standard","I39";
;
CDS_LIB"mstr_standard"
BODY_TYPE"PLUMBING"
HDL_TAP"TRUE";
"B \NAC \NWC"6;
"S \NAC"
BN"6"82;
%"TAP"
"1","(-6000,2475)","0","mstr_standard","I40";
;
CDS_LIB"mstr_standard"
BODY_TYPE"PLUMBING"
HDL_TAP"TRUE";
"B \NAC \NWC"6;
"S \NAC"
BN"7"83;
%"TAP"
"1","(-6000,2525)","0","mstr_standard","I41";
;
CDS_LIB"mstr_standard"
BODY_TYPE"PLUMBING"
HDL_TAP"TRUE";
"B \NAC \NWC"6;
"S \NAC"
BN"8"84;
%"TAP"
"1","(-6000,2625)","0","mstr_standard","I42";
;
CDS_LIB"mstr_standard"
BODY_TYPE"PLUMBING"
HDL_TAP"TRUE";
"B \NAC \NWC"6;
"S \NAC"
BN"10"86;
%"TAP"
"1","(-6000,2575)","0","mstr_standard","I43";
;
CDS_LIB"mstr_standard"
BODY_TYPE"PLUMBING"
HDL_TAP"TRUE";
"B \NAC \NWC"6;
"S \NAC"
BN"9"85;
%"TAP"
"1","(-6000,2675)","0","mstr_standard","I44";
;
CDS_LIB"mstr_standard"
BODY_TYPE"PLUMBING"
HDL_TAP"TRUE";
"B \NAC \NWC"6;
"S \NAC"
BN"11"87;
%"TAP"
"1","(-6000,2725)","0","mstr_standard","I45";
;
CDS_LIB"mstr_standard"
BODY_TYPE"PLUMBING"
HDL_TAP"TRUE";
"B \NAC \NWC"6;
"S \NAC"
BN"12"88;
%"TAP"
"1","(-6000,2775)","0","mstr_standard","I46";
;
CDS_LIB"mstr_standard"
BODY_TYPE"PLUMBING"
HDL_TAP"TRUE";
"B \NAC \NWC"6;
"S \NAC"
BN"13"89;
%"TAP"
"1","(-6000,2825)","0","mstr_standard","I47";
;
CDS_LIB"mstr_standard"
BODY_TYPE"PLUMBING"
HDL_TAP"TRUE";
"B \NAC \NWC"6;
"S \NAC"
BN"14"90;
%"TAP"
"1","(-6000,2875)","0","mstr_standard","I48";
;
CDS_LIB"mstr_standard"
BODY_TYPE"PLUMBING"
HDL_TAP"TRUE";
"B \NAC \NWC"6;
"S \NAC"
BN"15"91;
%"TAP"
"1","(-6000,2925)","0","mstr_standard","I49";
;
CDS_LIB"mstr_standard"
BODY_TYPE"PLUMBING"
HDL_TAP"TRUE";
"B \NAC \NWC"6;
"S \NAC"
BN"16"92;
%"TAP"
"1","(-6000,2975)","0","mstr_standard","I50";
;
CDS_LIB"mstr_standard"
BODY_TYPE"PLUMBING"
HDL_TAP"TRUE";
"B \NAC \NWC"6;
"S \NAC"
BN"17"93;
%"TAP"
"1","(-6000,3025)","0","mstr_standard","I51";
;
CDS_LIB"mstr_standard"
BODY_TYPE"PLUMBING"
HDL_TAP"TRUE";
"B \NAC \NWC"6;
"S \NAC"
BN"18"94;
%"TAP"
"1","(-6000,3075)","0","mstr_standard","I52";
;
CDS_LIB"mstr_standard"
BODY_TYPE"PLUMBING"
HDL_TAP"TRUE";
"B \NAC \NWC"6;
"S \NAC"
BN"19"95;
%"TAP"
"1","(-6000,3125)","0","mstr_standard","I53";
;
CDS_LIB"mstr_standard"
BODY_TYPE"PLUMBING"
HDL_TAP"TRUE";
"B \NAC \NWC"6;
"S \NAC"
BN"20"96;
%"TAP"
"1","(-6000,3175)","0","mstr_standard","I54";
;
CDS_LIB"mstr_standard"
BODY_TYPE"PLUMBING"
HDL_TAP"TRUE";
"B \NAC \NWC"6;
"S \NAC"
BN"21"97;
%"TAP"
"1","(-6000,3225)","0","mstr_standard","I55";
;
CDS_LIB"mstr_standard"
BODY_TYPE"PLUMBING"
HDL_TAP"TRUE";
"B \NAC \NWC"6;
"S \NAC"
BN"22"98;
%"TAP"
"1","(-6000,3275)","0","mstr_standard","I56";
;
CDS_LIB"mstr_standard"
BODY_TYPE"PLUMBING"
HDL_TAP"TRUE";
"B \NAC \NWC"6;
"S \NAC"
BN"23"99;
%"TAP"
"1","(-6000,3325)","0","mstr_standard","I57";
;
CDS_LIB"mstr_standard"
BODY_TYPE"PLUMBING"
HDL_TAP"TRUE";
"B \NAC \NWC"6;
"S \NAC"
BN"24"100;
%"TAP"
"1","(-6000,3375)","0","mstr_standard","I58";
;
CDS_LIB"mstr_standard"
BODY_TYPE"PLUMBING"
HDL_TAP"TRUE";
"B \NAC \NWC"6;
"S \NAC"
BN"25"101;
%"TAP"
"1","(-6000,3425)","0","mstr_standard","I59";
;
CDS_LIB"mstr_standard"
BODY_TYPE"PLUMBING"
HDL_TAP"TRUE";
"B \NAC \NWC"6;
"S \NAC"
BN"26"102;
%"TAP"
"1","(-6000,3475)","0","mstr_standard","I60";
;
CDS_LIB"mstr_standard"
BODY_TYPE"PLUMBING"
HDL_TAP"TRUE";
"B \NAC \NWC"6;
"S \NAC"
BN"27"103;
%"TAP"
"1","(-6000,3525)","0","mstr_standard","I61";
;
CDS_LIB"mstr_standard"
BODY_TYPE"PLUMBING"
HDL_TAP"TRUE";
"B \NAC \NWC"6;
"S \NAC"
BN"28"104;
%"TAP"
"1","(-6000,3575)","0","mstr_standard","I62";
;
CDS_LIB"mstr_standard"
BODY_TYPE"PLUMBING"
HDL_TAP"TRUE";
"B \NAC \NWC"6;
"S \NAC"
BN"29"105;
%"TAP"
"1","(-6000,3625)","0","mstr_standard","I63";
;
CDS_LIB"mstr_standard"
BODY_TYPE"PLUMBING"
HDL_TAP"TRUE";
"B \NAC \NWC"6;
"S \NAC"
BN"30"106;
%"VCC_CORE"
"1","(-8575,3350)","0","mstr_symbols","I7";
;
HDL_POWER"P3V3_STBY"
CDS_LIB"mstr_symbols"
VOLTAGE"3.3"
ROOM"PVCCINFAON_CPU1_CTRL";
"A"24;
%"TAP"
"1","(-7700,3675)","2","mstr_standard","I71";
;
CDS_LIB"mstr_standard"
BODY_TYPE"PLUMBING"
HDL_TAP"TRUE";
"B \NAC \NWC"1;
"S \NAC"
BN"2"153;
%"TAP"
"1","(-7700,3725)","2","mstr_standard","I72";
;
CDS_LIB"mstr_standard"
BODY_TYPE"PLUMBING"
HDL_TAP"TRUE";
"B \NAC \NWC"1;
"S \NAC"
BN"3"154;
%"TAP"
"1","(-7700,3825)","2","mstr_standard","I73";
;
CDS_LIB"mstr_standard"
BODY_TYPE"PLUMBING"
HDL_TAP"TRUE";
"B \NAC \NWC"1;
"S \NAC"
BN"5"155;
%"TAP"
"1","(-7700,3875)","2","mstr_standard","I74";
;
CDS_LIB"mstr_standard"
BODY_TYPE"PLUMBING"
HDL_TAP"TRUE";
"B \NAC \NWC"1;
"S \NAC"
BN"6"156;
%"TAP"
"1","(-7700,3775)","2","mstr_standard","I75";
;
CDS_LIB"mstr_standard"
BODY_TYPE"PLUMBING"
HDL_TAP"TRUE";
"B \NAC \NWC"1;
"S \NAC"
BN"4"173;
%"TAP"
"1","(-7700,3925)","2","mstr_standard","I76";
;
CDS_LIB"mstr_standard"
BODY_TYPE"PLUMBING"
HDL_TAP"TRUE";
"B \NAC \NWC"1;
"S \NAC"
BN"7"174;
%"TAP"
"1","(-7700,4625)","2","mstr_standard","I77";
;
CDS_LIB"mstr_standard"
BODY_TYPE"PLUMBING"
HDL_TAP"TRUE";
"B \NAC \NWC"3;
"S \NAC"
BN"0"169;
%"TAP"
"1","(-7700,4675)","2","mstr_standard","I78";
;
CDS_LIB"mstr_standard"
BODY_TYPE"PLUMBING"
HDL_TAP"TRUE";
"B \NAC \NWC"3;
"S \NAC"
BN"1"167;
%"TAP"
"1","(-7700,4725)","2","mstr_standard","I79";
;
CDS_LIB"mstr_standard"
BODY_TYPE"PLUMBING"
HDL_TAP"TRUE";
"B \NAC \NWC"3;
"S \NAC"
BN"2"165;
%"TAP"
"1","(-7700,4775)","2","mstr_standard","I80";
;
CDS_LIB"mstr_standard"
BODY_TYPE"PLUMBING"
HDL_TAP"TRUE";
"B \NAC \NWC"3;
"S \NAC"
BN"3"163;
%"TAP"
"1","(-7700,4825)","2","mstr_standard","I81";
;
CDS_LIB"mstr_standard"
BODY_TYPE"PLUMBING"
HDL_TAP"TRUE";
"B \NAC \NWC"3;
"S \NAC"
BN"4"161;
%"TAP"
"1","(-7700,4925)","2","mstr_standard","I82";
;
CDS_LIB"mstr_standard"
BODY_TYPE"PLUMBING"
HDL_TAP"TRUE";
"B \NAC \NWC"3;
"S \NAC"
BN"6"157;
%"TAP"
"1","(-7700,4875)","2","mstr_standard","I83";
;
CDS_LIB"mstr_standard"
BODY_TYPE"PLUMBING"
HDL_TAP"TRUE";
"B \NAC \NWC"3;
"S \NAC"
BN"5"159;
%"TAP"
"1","(-7700,5075)","2","mstr_standard","I84";
;
CDS_LIB"mstr_standard"
BODY_TYPE"PLUMBING"
HDL_TAP"TRUE";
"B \NAC \NWC"2;
"S \NAC"
BN"1"168;
%"TAP"
"1","(-7700,5125)","2","mstr_standard","I85";
;
CDS_LIB"mstr_standard"
BODY_TYPE"PLUMBING"
HDL_TAP"TRUE";
"B \NAC \NWC"2;
"S \NAC"
BN"2"166;
%"TAP"
"1","(-7700,5175)","2","mstr_standard","I86";
;
CDS_LIB"mstr_standard"
BODY_TYPE"PLUMBING"
HDL_TAP"TRUE";
"B \NAC \NWC"2;
"S \NAC"
BN"3"164;
%"TAP"
"1","(-7700,5025)","2","mstr_standard","I87";
;
CDS_LIB"mstr_standard"
BODY_TYPE"PLUMBING"
HDL_TAP"TRUE";
"B \NAC \NWC"2;
"S \NAC"
BN"0"170;
%"TAP"
"1","(-7700,5275)","2","mstr_standard","I88";
;
CDS_LIB"mstr_standard"
BODY_TYPE"PLUMBING"
HDL_TAP"TRUE";
"B \NAC \NWC"2;
"S \NAC"
BN"5"160;
%"TAP"
"1","(-7700,5325)","2","mstr_standard","I89";
;
CDS_LIB"mstr_standard"
BODY_TYPE"PLUMBING"
HDL_TAP"TRUE";
"B \NAC \NWC"2;
"S \NAC"
BN"6"158;
%"TAP"
"1","(-7700,5225)","2","mstr_standard","I90";
;
CDS_LIB"mstr_standard"
BODY_TYPE"PLUMBING"
HDL_TAP"TRUE";
"B \NAC \NWC"2;
"S \NAC"
BN"4"162;
%"TAP"
"1","(-6000,3675)","0","mstr_standard","I91";
;
CDS_LIB"mstr_standard"
BODY_TYPE"PLUMBING"
HDL_TAP"TRUE";
"B \NAC \NWC"6;
"S \NAC"
BN"31"107;
%"TAP"
"1","(-6000,3775)","0","mstr_standard","I92";
;
CDS_LIB"mstr_standard"
BODY_TYPE"PLUMBING"
HDL_TAP"TRUE";
"B \NAC \NWC"5;
"S \NAC"
BN"0"108;
%"TAP"
"1","(-6000,3825)","0","mstr_standard","I93";
;
CDS_LIB"mstr_standard"
BODY_TYPE"PLUMBING"
HDL_TAP"TRUE";
"B \NAC \NWC"5;
"S \NAC"
BN"1"109;
%"TAP"
"1","(-6000,3875)","0","mstr_standard","I94";
;
CDS_LIB"mstr_standard"
BODY_TYPE"PLUMBING"
HDL_TAP"TRUE";
"B \NAC \NWC"5;
"S \NAC"
BN"2"110;
%"TAP"
"1","(-6000,3925)","0","mstr_standard","I95";
;
CDS_LIB"mstr_standard"
BODY_TYPE"PLUMBING"
HDL_TAP"TRUE";
"B \NAC \NWC"5;
"S \NAC"
BN"3"111;
%"TAP"
"1","(-6000,3975)","0","mstr_standard","I96";
;
CDS_LIB"mstr_standard"
BODY_TYPE"PLUMBING"
HDL_TAP"TRUE";
"B \NAC \NWC"5;
"S \NAC"
BN"4"112;
%"TAP"
"1","(-6000,4025)","0","mstr_standard","I97";
;
CDS_LIB"mstr_standard"
BODY_TYPE"PLUMBING"
HDL_TAP"TRUE";
"B \NAC \NWC"5;
"S \NAC"
BN"5"113;
%"TAP"
"1","(-6000,4075)","0","mstr_standard","I98";
;
CDS_LIB"mstr_standard"
BODY_TYPE"PLUMBING"
HDL_TAP"TRUE";
"B \NAC \NWC"5;
"S \NAC"
BN"6"114;
%"TAP"
"1","(-6000,4125)","0","mstr_standard","I99";
;
CDS_LIB"mstr_standard"
BODY_TYPE"PLUMBING"
HDL_TAP"TRUE";
"B \NAC \NWC"5;
"S \NAC"
BN"7"115;
END.
